(kicad_pcb
	(version 20241229)
	(generator "pcbnew")
	(generator_version "9.0")
	(general
		(thickness 1.294)
		(legacy_teardrops no)
	)
	(paper "A3")
	(title_block
		(title "Kintex 410T devboard")
		(date "2024-04-03")
		(rev "1.1.2")
		(comment 9 "footprints 679-684 of 975")
	)
	(layers
		(0 "F.Cu" mixed)
		(4 "In1.Cu" power)
		(6 "In2.Cu" power)
		(8 "In3.Cu" mixed)
		(10 "In4.Cu" power)
		(12 "In5.Cu" mixed)
		(14 "In6.Cu" power)
		(16 "In7.Cu" mixed)
		(18 "In8.Cu" power)
		(2 "B.Cu" mixed)
		(9 "F.Adhes" user "F.Adhesive")
		(11 "B.Adhes" user "B.Adhesive")
		(13 "F.Paste" user)
		(15 "B.Paste" user)
		(5 "F.SilkS" user "F.Silkscreen")
		(7 "B.SilkS" user "B.Silkscreen")
		(1 "F.Mask" user)
		(3 "B.Mask" user)
		(17 "Dwgs.User" user "User.Drawings")
		(19 "Cmts.User" user "User.Comments")
		(21 "Eco1.User" user "User.Eco1")
		(23 "Eco2.User" user "User.Eco2")
		(25 "Edge.Cuts" user)
		(27 "Margin" user)
		(31 "F.CrtYd" user "F.Courtyard")
		(29 "B.CrtYd" user "B.Courtyard")
		(35 "F.Fab" user)
		(33 "B.Fab" user)
	)
	(footprint "antmicro-footprints:R_0402_1005Metric"
		(layer "B.Cu")
		(at 229 155.2)
		(descr "Resistor SMD 0402")
		(tags "resistor SMD 0402")
		(property "Reference" "R229"
			(at 3.65 0.375 180)
			(layer "B.SilkS")
			(effects
				(font
					(size 0.7 0.7)
					(thickness 0.15)
				)
				(justify left bottom mirror)
			)
		)
		(property "Value" "R_2k2_0402"
			(at 0 -1.4 180)
			(layer "B.Fab")
			(effects
				(font
					(size 0.7 0.7)
					(thickness 0.15)
				)
				(justify left bottom mirror)
			)
		)
		(property "Description" "SMD Chip Resistor, 2.2 kohm, ± 1%, 62.5 mW, 0402 [1005 Metric], Thick Film, General Purpose"
			(at 0 0 0)
			(layer "F.Fab")
			(hide yes)
			(effects
				(font
					(size 1.27 1.27)
					(thickness 0.15)
				)
			)
		)
		(property "Author" "Antmicro"
			(at 0 0 0)
			(layer "B.Fab")
			(hide yes)
			(effects
				(font
					(size 1 1)
					(thickness 0.15)
				)
				(justify mirror)
			)
		)
		(property "License" "Apache-2.0"
			(at 0 0 0)
			(layer "B.Fab")
			(hide yes)
			(effects
				(font
					(size 1 1)
					(thickness 0.15)
				)
				(justify mirror)
			)
		)
		(property "MPN" "CR0402-FX-2201GLF"
			(at 0 0 0)
			(layer "B.Fab")
			(hide yes)
			(effects
				(font
					(size 1 1)
					(thickness 0.15)
				)
				(justify mirror)
			)
		)
		(property "Manufacturer" "Bourns"
			(at 0 0 0)
			(layer "B.Fab")
			(hide yes)
			(effects
				(font
					(size 1 1)
					(thickness 0.15)
				)
				(justify mirror)
			)
		)
		(property "Tolerance" "1%"
			(at 0 0 0)
			(layer "B.Fab")
			(hide yes)
			(effects
				(font
					(size 1 1)
					(thickness 0.15)
				)
				(justify mirror)
			)
		)
		(property "Val" "2k2"
			(at 0 0 0)
			(layer "B.Fab")
			(hide yes)
			(effects
				(font
					(size 1 1)
					(thickness 0.15)
				)
				(justify mirror)
			)
		)
		(sheetname "HDMI + Ethernet")
		(sheetfile "hdmi-ethernet.kicad_sch")
		(attr smd)
		(fp_rect
			(start -0.925 0.47)
			(end 0.925 -0.47)
			(stroke
				(width 0.05)
				(type default)
			)
			(fill no)
			(layer "B.CrtYd")
		)
		(fp_rect
			(start -0.5 0.25)
			(end 0.5 -0.25)
			(stroke
				(width 0.15)
				(type solid)
			)
			(fill no)
			(layer "B.Fab")
		)
		(pad "1" smd roundrect
			(at -0.48 0)
			(size 0.59 0.64)
			(layers "B.Cu" "B.Mask" "B.Paste")
			(roundrect_rratio 0.25)
			(net 847 "/HDMI + Ethernet/ETH_LED_LINK-")
			(pintype "passive")
		)
		(pad "2" smd roundrect
			(at 0.48 0)
			(size 0.59 0.64)
			(layers "B.Cu" "B.Mask" "B.Paste")
			(roundrect_rratio 0.25)
			(net 1 "GND")
			(pintype "passive")
		)
	)
	(footprint "antmicro-footprints:C_0402_1005Metric"
		(layer "B.Cu")
		(at 190.5 141 90)
		(descr "Capacitor SMD 0402")
		(tags "capacitor SMD 0402")
		(property "Reference" "C79"
			(at 0.975 -0.475 270)
			(layer "B.SilkS")
			(effects
				(font
					(size 0.7 0.7)
					(thickness 0.15)
				)
				(justify left bottom mirror)
			)
		)
		(property "Value" "C_100n_0402"
			(at 0 -1.169 270)
			(layer "B.Fab")
			(effects
				(font
					(size 0.7 0.7)
					(thickness 0.15)
				)
				(justify left bottom mirror)
			)
		)
		(property "Description" "SMD Multilayer Ceramic Capacitor, 0.1 µF, 50 V, 0402 [1005 Metric], ± 10%, X5R, GRM Series"
			(at 0 0 90)
			(layer "F.Fab")
			(hide yes)
			(effects
				(font
					(size 1.27 1.27)
					(thickness 0.15)
				)
			)
		)
		(property "Author" "Antmicro"
			(at 331.5 -49.5 0)
			(layer "B.Fab")
			(hide yes)
			(effects
				(font
					(size 1 1)
					(thickness 0.15)
				)
				(justify mirror)
			)
		)
		(property "Dielectric" "X5R"
			(at 331.5 -49.5 0)
			(layer "B.Fab")
			(hide yes)
			(effects
				(font
					(size 1 1)
					(thickness 0.15)
				)
				(justify mirror)
			)
		)
		(property "License" "Apache-2.0"
			(at 331.5 -49.5 0)
			(layer "B.Fab")
			(hide yes)
			(effects
				(font
					(size 1 1)
					(thickness 0.15)
				)
				(justify mirror)
			)
		)
		(property "MPN" "GRM155R61H104KE14D"
			(at 331.5 -49.5 0)
			(layer "B.Fab")
			(hide yes)
			(effects
				(font
					(size 1 1)
					(thickness 0.15)
				)
				(justify mirror)
			)
		)
		(property "Manufacturer" "Murata"
			(at 331.5 -49.5 0)
			(layer "B.Fab")
			(hide yes)
			(effects
				(font
					(size 1 1)
					(thickness 0.15)
				)
				(justify mirror)
			)
		)
		(property "Val" "100n"
			(at 331.5 -49.5 0)
			(layer "B.Fab")
			(hide yes)
			(effects
				(font
					(size 1 1)
					(thickness 0.15)
				)
				(justify mirror)
			)
		)
		(property "Voltage" "50V"
			(at 331.5 -49.5 0)
			(layer "B.Fab")
			(hide yes)
			(effects
				(font
					(size 1 1)
					(thickness 0.15)
				)
				(justify mirror)
			)
		)
		(sheetname "FPGA Bank 33 & 34")
		(sheetfile "fpga-bank-33-34.kicad_sch")
		(attr smd)
		(fp_rect
			(start -0.925 0.47)
			(end 0.925 -0.47)
			(stroke
				(width 0.05)
				(type default)
			)
			(fill no)
			(layer "B.CrtYd")
		)
		(fp_line
			(start 0.504 -0.248)
			(end -0.494 -0.248)
			(stroke
				(width 0.15)
				(type solid)
			)
			(layer "B.Fab")
		)
		(fp_line
			(start -0.494 -0.248)
			(end -0.494 0.25)
			(stroke
				(width 0.15)
				(type solid)
			)
			(layer "B.Fab")
		)
		(fp_line
			(start 0.504 0.25)
			(end 0.504 -0.248)
			(stroke
				(width 0.15)
				(type solid)
			)
			(layer "B.Fab")
		)
		(fp_line
			(start -0.494 0.25)
			(end 0.504 0.25)
			(stroke
				(width 0.15)
				(type solid)
			)
			(layer "B.Fab")
		)
		(pad "1" smd roundrect
			(at -0.48 0 90)
			(size 0.59 0.64)
			(layers "B.Cu" "B.Mask" "B.Paste")
			(roundrect_rratio 0.25)
			(net 1 "GND")
			(pintype "passive")
		)
		(pad "2" smd roundrect
			(at 0.48 0 90)
			(size 0.59 0.64)
			(layers "B.Cu" "B.Mask" "B.Paste")
			(roundrect_rratio 0.25)
			(net 25 "+1V35")
			(pintype "passive")
		)
	)
	(footprint "antmicro-footprints:R_0402_1005Metric"
		(layer "B.Cu")
		(at 236.299999 84.7 90)
		(descr "Resistor SMD 0402")
		(tags "resistor SMD 0402")
		(property "Reference" "R124"
			(at -0.775 0.400001 270)
			(layer "B.SilkS")
			(effects
				(font
					(size 0.7 0.7)
					(thickness 0.15)
				)
				(justify left bottom mirror)
			)
		)
		(property "Value" "R_100R_0402"
			(at 0 -1.4 270)
			(layer "B.Fab")
			(effects
				(font
					(size 0.7 0.7)
					(thickness 0.15)
				)
				(justify left bottom mirror)
			)
		)
		(property "Description" "SMD Chip Resistor, 100 ohm, ± 1%, 62.5 mW, 0402 [1005 Metric], Thick Film, General Purpose"
			(at 0 0 90)
			(layer "F.Fab")
			(hide yes)
			(effects
				(font
					(size 1.27 1.27)
					(thickness 0.15)
				)
			)
		)
		(property "Author" "Antmicro"
			(at 320.999999 -151.599999 0)
			(layer "B.Fab")
			(hide yes)
			(effects
				(font
					(size 1 1)
					(thickness 0.15)
				)
				(justify mirror)
			)
		)
		(property "License" "Apache-2.0"
			(at 320.999999 -151.599999 0)
			(layer "B.Fab")
			(hide yes)
			(effects
				(font
					(size 1 1)
					(thickness 0.15)
				)
				(justify mirror)
			)
		)
		(property "MPN" "CR0402-FX-1000GLF"
			(at 320.999999 -151.599999 0)
			(layer "B.Fab")
			(hide yes)
			(effects
				(font
					(size 1 1)
					(thickness 0.15)
				)
				(justify mirror)
			)
		)
		(property "Manufacturer" "Bourns"
			(at 320.999999 -151.599999 0)
			(layer "B.Fab")
			(hide yes)
			(effects
				(font
					(size 1 1)
					(thickness 0.15)
				)
				(justify mirror)
			)
		)
		(property "Tolerance" "1%"
			(at 320.999999 -151.599999 0)
			(layer "B.Fab")
			(hide yes)
			(effects
				(font
					(size 1 1)
					(thickness 0.15)
				)
				(justify mirror)
			)
		)
		(property "Val" "100R"
			(at 320.999999 -151.599999 0)
			(layer "B.Fab")
			(hide yes)
			(effects
				(font
					(size 1 1)
					(thickness 0.15)
				)
				(justify mirror)
			)
		)
		(sheetname "User GPIO + LED + button + DIP switch")
		(sheetfile "user-gpio.kicad_sch")
		(attr smd)
		(fp_rect
			(start -0.925 0.47)
			(end 0.925 -0.47)
			(stroke
				(width 0.05)
				(type default)
			)
			(fill no)
			(layer "B.CrtYd")
		)
		(fp_rect
			(start -0.5 0.25)
			(end 0.5 -0.25)
			(stroke
				(width 0.15)
				(type solid)
			)
			(fill no)
			(layer "B.Fab")
		)
		(pad "1" smd roundrect
			(at -0.48 0 90)
			(size 0.59 0.64)
			(layers "B.Cu" "B.Mask" "B.Paste")
			(roundrect_rratio 0.25)
			(net 462 "/FPGA Bank 12 & 13/PMOD_B.IO1")
			(pintype "passive")
		)
		(pad "2" smd roundrect
			(at 0.48 0 90)
			(size 0.59 0.64)
			(layers "B.Cu" "B.Mask" "B.Paste")
			(roundrect_rratio 0.25)
			(net 817 "/User GPIO + LED + button + DIP switch/PMOD_B_1")
			(pintype "passive")
		)
	)
	(footprint "antmicro-footprints:R_0402_1005Metric"
		(layer "B.Cu")
		(at 225.9 125.8 -90)
		(descr "Resistor SMD 0402")
		(tags "resistor SMD 0402")
		(property "Reference" "R111"
			(at -1.325 -1.35 90)
			(layer "B.SilkS")
			(effects
				(font
					(size 0.7 0.7)
					(thickness 0.15)
				)
				(justify left bottom mirror)
			)
		)
		(property "Value" "R_1k_0402"
			(at 0 -1.4 90)
			(layer "B.Fab")
			(effects
				(font
					(size 0.7 0.7)
					(thickness 0.15)
				)
				(justify left bottom mirror)
			)
		)
		(property "Description" "SMD Chip Resistor, 1 kohm, ± 1%, 63 mW, 0402 [1005 Metric], Thick Film, General Purpose"
			(at 0 0 270)
			(layer "F.Fab")
			(hide yes)
			(effects
				(font
					(size 1.27 1.27)
					(thickness 0.15)
				)
			)
		)
		(property "Author" "Antmicro"
			(at 100.1 351.7 0)
			(layer "B.Fab")
			(hide yes)
			(effects
				(font
					(size 1 1)
					(thickness 0.15)
				)
				(justify mirror)
			)
		)
		(property "License" "Apache-2.0"
			(at 100.1 351.7 0)
			(layer "B.Fab")
			(hide yes)
			(effects
				(font
					(size 1 1)
					(thickness 0.15)
				)
				(justify mirror)
			)
		)
		(property "MPN" "CR0402-FX-1001GLF"
			(at 100.1 351.7 0)
			(layer "B.Fab")
			(hide yes)
			(effects
				(font
					(size 1 1)
					(thickness 0.15)
				)
				(justify mirror)
			)
		)
		(property "Manufacturer" "Bourns"
			(at 100.1 351.7 0)
			(layer "B.Fab")
			(hide yes)
			(effects
				(font
					(size 1 1)
					(thickness 0.15)
				)
				(justify mirror)
			)
		)
		(property "Tolerance" "1%"
			(at 100.1 351.7 0)
			(layer "B.Fab")
			(hide yes)
			(effects
				(font
					(size 1 1)
					(thickness 0.15)
				)
				(justify mirror)
			)
		)
		(property "Val" "1k"
			(at 100.1 351.7 0)
			(layer "B.Fab")
			(hide yes)
			(effects
				(font
					(size 1 1)
					(thickness 0.15)
				)
				(justify mirror)
			)
		)
		(sheetname "User GPIO + LED + button + DIP switch")
		(sheetfile "user-gpio.kicad_sch")
		(attr smd)
		(fp_rect
			(start -0.925 0.47)
			(end 0.925 -0.47)
			(stroke
				(width 0.05)
				(type default)
			)
			(fill no)
			(layer "B.CrtYd")
		)
		(fp_rect
			(start -0.5 0.25)
			(end 0.5 -0.25)
			(stroke
				(width 0.15)
				(type solid)
			)
			(fill no)
			(layer "B.Fab")
		)
		(pad "1" smd roundrect
			(at -0.48 0 270)
			(size 0.59 0.64)
			(layers "B.Cu" "B.Mask" "B.Paste")
			(roundrect_rratio 0.25)
			(net 801 "/User GPIO + LED + button + DIP switch/FAN_PWM_PIN")
			(pintype "passive")
		)
		(pad "2" smd roundrect
			(at 0.48 0 270)
			(size 0.59 0.64)
			(layers "B.Cu" "B.Mask" "B.Paste")
			(roundrect_rratio 0.25)
			(net 703 "+5V")
			(pintype "passive")
		)
	)
	(footprint "antmicro-footprints:C_0201"
		(layer "B.Cu")
		(at 201.5 134.45 180)
		(descr "Capacitor SMD 0201")
		(tags "capacitor SMD 0201")
		(property "Reference" "C34"
			(at -26.9 28.1 0)
			(layer "B.SilkS")
			(effects
				(font
					(size 0.7 0.7)
					(thickness 0.15)
				)
				(justify left bottom mirror)
			)
		)
		(property "Value" "C_4u7_0201"
			(at 0 -1.4 0)
			(layer "B.Fab")
			(effects
				(font
					(size 0.7 0.7)
					(thickness 0.15)
				)
				(justify left bottom mirror)
			)
		)
		(property "Description" "SMD Multilayer Ceramic Capacitor, 4.7 µF, 6.3 V, 0201 [0603 Metric], ± 20%, X5R, GRM Series"
			(at 0 0 180)
			(layer "F.Fab")
			(hide yes)
			(effects
				(font
					(size 1.27 1.27)
					(thickness 0.15)
				)
			)
		)
		(property "Author" "Antmicro"
			(at 403 268.9 0)
			(layer "B.Fab")
			(hide yes)
			(effects
				(font
					(size 1 1)
					(thickness 0.15)
				)
				(justify mirror)
			)
		)
		(property "Dielectric" ""
			(at 403 268.9 0)
			(layer "B.Fab")
			(hide yes)
			(effects
				(font
					(size 1 1)
					(thickness 0.15)
				)
				(justify mirror)
			)
		)
		(property "License" "Apache-2.0"
			(at 403 268.9 0)
			(layer "B.Fab")
			(hide yes)
			(effects
				(font
					(size 1 1)
					(thickness 0.15)
				)
				(justify mirror)
			)
		)
		(property "MPN" "GRM035R60J475ME15D"
			(at 403 268.9 0)
			(layer "B.Fab")
			(hide yes)
			(effects
				(font
					(size 1 1)
					(thickness 0.15)
				)
				(justify mirror)
			)
		)
		(property "Manufacturer" "Murata"
			(at 403 268.9 0)
			(layer "B.Fab")
			(hide yes)
			(effects
				(font
					(size 1 1)
					(thickness 0.15)
				)
				(justify mirror)
			)
		)
		(property "Val" "4u7"
			(at 403 268.9 0)
			(layer "B.Fab")
			(hide yes)
			(effects
				(font
					(size 1 1)
					(thickness 0.15)
				)
				(justify mirror)
			)
		)
		(property "Voltage" ""
			(at 403 268.9 0)
			(layer "B.Fab")
			(hide yes)
			(effects
				(font
					(size 1 1)
					(thickness 0.15)
				)
				(justify mirror)
			)
		)
		(sheetname "FPGA supply")
		(sheetfile "fpga-supply.kicad_sch")
		(attr smd)
		(fp_rect
			(start -0.7 0.35)
			(end 0.7 -0.35)
			(stroke
				(width 0.05)
				(type default)
			)
			(fill no)
			(layer "B.CrtYd")
		)
		(fp_rect
			(start 0.3 -0.15)
			(end -0.301 0.149)
			(stroke
				(width 0.15)
				(type solid)
			)
			(fill no)
			(layer "B.Fab")
		)
		(pad "" smd roundrect
			(at -0.349 0.002 180)
			(size 0.318 0.36)
			(layers "B.Paste")
			(roundrect_rratio 0.25)
		)
		(pad "" smd roundrect
			(at 0.341 0.002 180)
			(size 0.318 0.36)
			(layers "B.Paste")
			(roundrect_rratio 0.25)
		)
		(pad "1" smd roundrect
			(at -0.321 0.002 180)
			(size 0.46 0.4)
			(layers "B.Cu" "B.Mask")
			(roundrect_rratio 0.25)
			(net 1 "GND")
			(pintype "passive")
		)
		(pad "2" smd roundrect
			(at 0.32 0.002 180)
			(size 0.46 0.4)
			(layers "B.Cu" "B.Mask")
			(roundrect_rratio 0.25)
			(net 650 "+1V0")
			(pintype "passive")
		)
	)
	(footprint "antmicro-footprints:R_0402_1005Metric"
		(layer "B.Cu")
		(at 172.75 176.7625 180)
		(descr "Resistor SMD 0402")
		(tags "resistor SMD 0402")
		(property "Reference" "R320"
			(at 0.725 -0.4125 0)
			(layer "B.SilkS")
			(effects
				(font
					(size 0.7 0.7)
					(thickness 0.15)
				)
				(justify left bottom mirror)
			)
		)
		(property "Value" "R_0R_0402"
			(at 0 -1.4 0)
			(layer "B.Fab")
			(effects
				(font
					(size 0.7 0.7)
					(thickness 0.15)
				)
				(justify left bottom mirror)
			)
		)
		(property "Description" "SMD Chip Resistor, Jumper, 0 ohm, 100 mW, 0402 [1005 Metric], Thick Film, General Purpose"
			(at 0 0 180)
			(layer "F.Fab")
			(hide yes)
			(effects
				(font
					(size 1.27 1.27)
					(thickness 0.15)
				)
			)
		)
		(property "Author" "Antmicro"
			(at 345.5 353.525 0)
			(layer "B.Fab")
			(hide yes)
			(effects
				(font
					(size 1 1)
					(thickness 0.15)
				)
				(justify mirror)
			)
		)
		(property "Current" "1A"
			(at 345.5 353.525 0)
			(layer "B.Fab")
			(hide yes)
			(effects
				(font
					(size 1 1)
					(thickness 0.15)
				)
				(justify mirror)
			)
		)
		(property "DNP" "DNP"
			(at 345.5 353.525 0)
			(layer "B.Fab")
			(hide yes)
			(effects
				(font
					(size 1 1)
					(thickness 0.15)
				)
				(justify mirror)
			)
		)
		(property "License" "Apache-2.0"
			(at 345.5 353.525 0)
			(layer "B.Fab")
			(hide yes)
			(effects
				(font
					(size 1 1)
					(thickness 0.15)
				)
				(justify mirror)
			)
		)
		(property "MPN" "ERJ2GE0R00X"
			(at 345.5 353.525 0)
			(layer "B.Fab")
			(hide yes)
			(effects
				(font
					(size 1 1)
					(thickness 0.15)
				)
				(justify mirror)
			)
		)
		(property "Manufacturer" "Panasonic"
			(at 345.5 353.525 0)
			(layer "B.Fab")
			(hide yes)
			(effects
				(font
					(size 1 1)
					(thickness 0.15)
				)
				(justify mirror)
			)
		)
		(property "Tolerance" ""
			(at 345.5 353.525 0)
			(layer "B.Fab")
			(hide yes)
			(effects
				(font
					(size 1 1)
					(thickness 0.15)
				)
				(justify mirror)
			)
		)
		(property "Val" "0R"
			(at 345.5 353.525 0)
			(layer "B.Fab")
			(hide yes)
			(effects
				(font
					(size 1 1)
					(thickness 0.15)
				)
				(justify mirror)
			)
		)
		(property "dnp" ""
			(at 345.5 353.525 0)
			(layer "B.Fab")
			(hide yes)
			(effects
				(font
					(size 1 1)
					(thickness 0.15)
				)
				(justify mirror)
			)
		)
		(property "exclude_from_bom" ""
			(at 345.5 353.525 0)
			(layer "B.Fab")
			(hide yes)
			(effects
				(font
					(size 1 1)
					(thickness 0.15)
				)
				(justify mirror)
			)
		)
		(sheetname "DC-DC Converters")
		(sheetfile "dc-dc.kicad_sch")
		(attr smd exclude_from_bom)
		(fp_rect
			(start -0.925 0.47)
			(end 0.925 -0.47)
			(stroke
				(width 0.05)
				(type default)
			)
			(fill no)
			(layer "B.CrtYd")
		)
		(fp_rect
			(start -0.5 0.25)
			(end 0.5 -0.25)
			(stroke
				(width 0.15)
				(type solid)
			)
			(fill no)
			(layer "B.Fab")
		)
		(pad "1" smd roundrect
			(at -0.48 0 180)
			(size 0.59 0.64)
			(layers "B.Cu" "B.Mask" "B.Paste")
			(roundrect_rratio 0.25)
			(net 965 "/DC-DC Converters/FB8")
			(pintype "passive")
		)
		(pad "2" smd roundrect
			(at 0.48 0 180)
			(size 0.59 0.64)
			(layers "B.Cu" "B.Mask" "B.Paste")
			(roundrect_rratio 0.25)
			(net 1216 "/DC-DC Converters/SENSE_1V35_P")
			(pintype "passive")
		)
	)
)
